# T6G (Grand Teton) — schematic netlist excerpt (pin names and nets, part order shuffled) for the footprints in the layout excerpt that follows; sources: Cadence DE-HDL packaged netlist, KiCad conversion of 04192023_DAF0TMB3IC0_F0TG_MB_C_brd_V02_OCP.brd

C1552  Q_CAP_DIFFBUS  DIFF BUS_0.22UF 6.3V 20% X6S  pkg C0201  page 65 : \1\ = P5E_CPU0_G3_TX_C_DN<13> ; \2\ = P5E_CPU0_G3_TX_DN<13>

PL13  Q_INDUCTOR4P_14  150NH IND  pkg L_TLM117513Q-151QL_11X7-5XA  page 202
  \1\  = SW_PVDDCR_CPU1_P0_SW4
  \2\  = IND_CPU1_P0_CPL3
  \3\  = GND
  \4\  = PVDDCR_CPU1_P0

R3665  Q_RES  100K 1% CHIP  pkg 0402LF  page 234 : A = USB_HUB_PGANG ; B = GND

(kicad_pcb
	(version 20260206)
	(generator "pcbnew")
	(generator_version "10.0")
	(general
		(thickness 1.6)
		(legacy_teardrops no)
	)
	(paper "A4")
	(title_block
		(title "04192023_DAF0TMB3IC0_F0TG_MB_C_brd_V02_OCP.brd")
		(comment 1 "Grand Teton / footprints 1955-1957 of 8354")
	)
	(layers
		(0 "F.Cu" signal "TOP")
		(4 "In1.Cu" signal "GND")
		(6 "In2.Cu" signal "IN1")
		(8 "In3.Cu" signal "GND1")
		(10 "In4.Cu" signal "IN2")
		(12 "In5.Cu" signal "GND2")
		(14 "In6.Cu" signal "IN3")
		(16 "In7.Cu" signal "GND3")
		(18 "In8.Cu" signal "VCC")
		(20 "In9.Cu" signal "VCC1")
		(22 "In10.Cu" signal "GND4")
		(24 "In11.Cu" signal "IN4")
		(26 "In12.Cu" signal "GND5")
		(28 "In13.Cu" signal "IN5")
		(30 "In14.Cu" signal "GND6")
		(32 "In15.Cu" signal "IN6")
		(34 "In16.Cu" signal "GND7")
		(2 "B.Cu" signal "BOTTOM")
		(9 "F.Adhes" user "F.Adhesive")
		(11 "B.Adhes" user "B.Adhesive")
		(13 "F.Paste" user "Package Geometry/Pastemask Top")
		(15 "B.Paste" user "Package Geometry/Pastemask Bottom")
		(5 "F.SilkS" user "Ref Des/Silkscreen Top")
		(7 "B.SilkS" user "Ref Des/Silkscreen Bottom")
		(1 "F.Mask" user "Board Geometry/Soldermask Top")
		(3 "B.Mask" user "Board Geometry/Soldermask Bottom")
		(17 "Dwgs.User" user "User.Drawings")
		(19 "Cmts.User" user "User.Comments")
		(21 "Eco1.User" user "User.Eco1")
		(23 "Eco2.User" user "User.Eco2")
		(25 "Edge.Cuts" user "Board Geometry/Outline")
		(27 "Margin" user)
		(31 "F.CrtYd" user "Package Geometry/Place Bound Top")
		(29 "B.CrtYd" user "Package Geometry/Place Bound Bottom")
		(35 "F.Fab" user "Ref Des/Assembly Top")
		(33 "B.Fab" user "Ref Des/Assembly Bottom")
	)
	(footprint ""
		(layer "F.Cu")
		(at 308.813962 -337.399122)
		(property "Reference" "PL13"
			(at -6.299962 -15.126208 0)
			(unlocked yes)
			(layer "F.SilkS")
			(effects
				(font
					(size 0.7874 0.5842)
					(thickness 0.1524)
				)
				(justify left)
			)
		)
		(property "Value" ""
			(at 0 0 0)
			(layer "F.Fab")
			(effects
				(font
					(size 1.27 1.27)
				)
			)
		)
		(duplicate_pad_numbers_are_jumpers no)
		(fp_line
			(start -3.750056 -5.500116)
			(end -2.393442 -5.500116)
			(stroke
				(width 0.1524)
				(type default)
			)
			(layer "F.SilkS")
		)
		(fp_line
			(start -3.750056 5.500116)
			(end -3.750056 -5.500116)
			(stroke
				(width 0.1524)
				(type default)
			)
			(layer "F.SilkS")
		)
		(fp_line
			(start -2.393442 5.500116)
			(end -3.750056 5.500116)
			(stroke
				(width 0.1524)
				(type default)
			)
			(layer "F.SilkS")
		)
		(fp_line
			(start 2.393442 5.500116)
			(end 3.750056 5.500116)
			(stroke
				(width 0.1524)
				(type default)
			)
			(layer "F.SilkS")
		)
		(fp_line
			(start 3.750056 -5.500116)
			(end 2.393442 -5.500116)
			(stroke
				(width 0.1524)
				(type default)
			)
			(layer "F.SilkS")
		)
		(fp_line
			(start 3.750056 5.500116)
			(end 3.750056 -5.500116)
			(stroke
				(width 0.1524)
				(type default)
			)
			(layer "F.SilkS")
		)
		(fp_poly
			(pts
				(xy -3.9116 -4.249928) (xy -4.3434 -4.034028) (xy -4.3434 -4.465828)
			)
			(stroke
				(width 0)
				(type default)
			)
			(fill yes)
			(layer "F.SilkS")
		)
		(fp_line
			(start -3.750056 -5.500116)
			(end -3.750056 5.500116)
			(stroke
				(width 0.1)
				(type default)
			)
			(layer "F.Fab")
		)
		(fp_line
			(start -3.750056 5.500116)
			(end 3.750056 5.500116)
			(stroke
				(width 0.1)
				(type default)
			)
			(layer "F.Fab")
		)
		(fp_line
			(start 3.750056 -5.500116)
			(end -3.750056 -5.500116)
			(stroke
				(width 0.1)
				(type default)
			)
			(layer "F.Fab")
		)
		(fp_line
			(start 3.750056 5.500116)
			(end 3.750056 -5.500116)
			(stroke
				(width 0.1)
				(type default)
			)
			(layer "F.Fab")
		)
		(fp_poly
			(pts
				(xy -4.9276 -4.757928) (xy -4.9276 -3.741928) (xy -3.9116 -4.249928)
			)
			(stroke
				(width 0)
				(type default)
			)
			(fill yes)
			(layer "F.Fab")
		)
		(pad "1" smd rect
			(at 0 -4.249928 270)
			(size 2.413 4.5212)
			(layers "F.Cu" "F.Mask" "F.Paste")
			(net "SW_PVDDCR_CPU1_P0_SW4")
		)
		(pad "2" smd rect
			(at 0 -1.175004 270)
			(size 1.3716 4.5212)
			(layers "F.Cu" "F.Mask" "F.Paste")
			(net "IND_CPU1_P0_CPL3")
		)
		(pad "3" smd rect
			(at 0 1.175004 270)
			(size 1.3716 4.5212)
			(layers "F.Cu" "F.Mask" "F.Paste")
			(net "GND")
		)
		(pad "4" smd rect
			(at 0 4.249928 270)
			(size 2.413 4.5212)
			(layers "F.Cu" "F.Mask" "F.Paste")
			(net "PVDDCR_CPU1_P0")
		)
	)
	(footprint ""
		(layer "F.Cu")
		(at 21.176996 -98.171508)
		(property "Reference" "R3665"
			(at 0 0 0)
			(layer "F.SilkS")
			(hide yes)
			(effects
				(font
					(size 1.27 1.27)
				)
			)
		)
		(property "Value" ""
			(at 0 0 0)
			(layer "F.Fab")
			(effects
				(font
					(size 1.27 1.27)
				)
			)
		)
		(duplicate_pad_numbers_are_jumpers no)
		(fp_line
			(start -0.7874 -0.4064)
			(end 0.7874 -0.4064)
			(stroke
				(width 0.1524)
				(type default)
			)
			(layer "F.SilkS")
		)
		(fp_line
			(start -0.7874 0.4064)
			(end -0.7874 -0.4064)
			(stroke
				(width 0.1524)
				(type default)
			)
			(layer "F.SilkS")
		)
		(fp_line
			(start 0.7874 -0.4064)
			(end 0.7874 0.4064)
			(stroke
				(width 0.1524)
				(type default)
			)
			(layer "F.SilkS")
		)
		(fp_line
			(start 0.7874 0.4064)
			(end -0.7874 0.4064)
			(stroke
				(width 0.1524)
				(type default)
			)
			(layer "F.SilkS")
		)
		(fp_line
			(start -0.67945 -0.305054)
			(end -0.12065 -0.305054)
			(stroke
				(width 0.1)
				(type default)
			)
			(layer "F.Fab")
		)
		(fp_line
			(start -0.67945 0.3048)
			(end -0.67945 -0.305054)
			(stroke
				(width 0.1)
				(type default)
			)
			(layer "F.Fab")
		)
		(fp_line
			(start -0.12065 -0.305054)
			(end -0.12065 -0.2794)
			(stroke
				(width 0.1)
				(type default)
			)
			(layer "F.Fab")
		)
		(fp_line
			(start -0.12065 -0.2794)
			(end 0.12065 -0.2794)
			(stroke
				(width 0.1)
				(type default)
			)
			(layer "F.Fab")
		)
		(fp_line
			(start -0.12065 0.2794)
			(end -0.12065 0.3048)
			(stroke
				(width 0.1)
				(type default)
			)
			(layer "F.Fab")
		)
		(fp_line
			(start -0.12065 0.3048)
			(end -0.67945 0.3048)
			(stroke
				(width 0.1)
				(type default)
			)
			(layer "F.Fab")
		)
		(fp_line
			(start 0.120396 0.2794)
			(end -0.12065 0.2794)
			(stroke
				(width 0.1)
				(type default)
			)
			(layer "F.Fab")
		)
		(fp_line
			(start 0.120396 0.3048)
			(end 0.120396 0.2794)
			(stroke
				(width 0.1)
				(type default)
			)
			(layer "F.Fab")
		)
		(fp_line
			(start 0.12065 -0.3048)
			(end 0.67945 -0.3048)
			(stroke
				(width 0.1)
				(type default)
			)
			(layer "F.Fab")
		)
		(fp_line
			(start 0.12065 -0.2794)
			(end 0.12065 -0.3048)
			(stroke
				(width 0.1)
				(type default)
			)
			(layer "F.Fab")
		)
		(fp_line
			(start 0.67945 -0.3048)
			(end 0.67945 0.3048)
			(stroke
				(width 0.1)
				(type default)
			)
			(layer "F.Fab")
		)
		(fp_line
			(start 0.67945 0.3048)
			(end 0.120396 0.3048)
			(stroke
				(width 0.1)
				(type default)
			)
			(layer "F.Fab")
		)
		(pad "1" smd circle
			(at -0.40005 0)
			(size 0 0)
			(layers "F.Cu" "F.Mask" "F.Paste")
			(net "USB_HUB_PGANG")
		)
		(pad "2" smd circle
			(at 0.40005 0)
			(size 0 0)
			(layers "F.Cu" "F.Mask" "F.Paste")
			(net "GND")
		)
	)
	(footprint ""
		(layer "F.Cu")
		(at 395.595348 -16.100298 90)
		(property "Reference" "C1552"
			(at 0 0 90)
			(layer "F.SilkS")
			(hide yes)
			(effects
				(font
					(size 1.27 1.27)
				)
			)
		)
		(property "Value" ""
			(at 0 0 90)
			(layer "F.Fab")
			(effects
				(font
					(size 1.27 1.27)
				)
			)
		)
		(duplicate_pad_numbers_are_jumpers no)
		(fp_line
			(start 0.299974 -0.150114)
			(end 0.299974 0.150114)
			(stroke
				(width 0.1)
				(type default)
			)
			(layer "F.Fab")
		)
		(fp_line
			(start -0.299974 -0.150114)
			(end 0.299974 -0.150114)
			(stroke
				(width 0.1)
				(type default)
			)
			(layer "F.Fab")
		)
		(fp_line
			(start 0.299974 0.150114)
			(end -0.299974 0.150114)
			(stroke
				(width 0.1)
				(type default)
			)
			(layer "F.Fab")
		)
		(fp_line
			(start -0.299974 0.150114)
			(end -0.299974 -0.150114)
			(stroke
				(width 0.1)
				(type default)
			)
			(layer "F.Fab")
		)
		(pad "1" smd rect
			(at -0.2667 0 90)
			(size 0.3048 0.381)
			(layers "F.Cu" "F.Mask" "F.Paste")
			(net "P5E_CPU0_G3_TX_C_DN<13>")
		)
		(pad "2" smd rect
			(at 0.2667 0 90)
			(size 0.3048 0.381)
			(layers "F.Cu" "F.Mask" "F.Paste")
			(net "P5E_CPU0_G3_TX_DN<13>")
		)
	)
)
